(kicad_pcb
	(version 20260206)
	(generator "pcbnew")
	(generator_version "10.0")
	(general
		(thickness 1.6)
		(legacy_teardrops no)
	)
	(paper "A4")
	(title_block
		(title "Bryce Canyon_R.DPB_16317-1_OCP.brd")
		(comment 1 "Bryce Canyon / footprints 940-946 of 2099")
	)
	(layers
		(0 "F.Cu" signal "TOP")
		(4 "In1.Cu" signal "L2GND")
		(6 "In2.Cu" signal "L3")
		(8 "In3.Cu" signal "L4VCC")
		(10 "In4.Cu" signal "L5VCC")
		(12 "In5.Cu" signal "L6")
		(14 "In6.Cu" signal "L7GND")
		(2 "B.Cu" signal "BOTTOM")
		(9 "F.Adhes" user "F.Adhesive")
		(11 "B.Adhes" user "B.Adhesive")
		(13 "F.Paste" user "Package Geometry/Pastemask Top")
		(15 "B.Paste" user "Package Geometry/Pastemask Bottom")
		(5 "F.SilkS" user "Ref Des/Silkscreen Top")
		(7 "B.SilkS" user "Ref Des/Silkscreen Bottom")
		(1 "F.Mask" user "Board Geometry/Soldermask Top")
		(3 "B.Mask" user "Board Geometry/Soldermask Bottom")
		(17 "Dwgs.User" user "User.Drawings")
		(19 "Cmts.User" user "User.Comments")
		(21 "Eco1.User" user "User.Eco1")
		(23 "Eco2.User" user "User.Eco2")
		(25 "Edge.Cuts" user "Board Geometry/Outline")
		(27 "Margin" user)
		(31 "F.CrtYd" user "Package Geometry/Place Bound Top")
		(29 "B.CrtYd" user "Package Geometry/Place Bound Bottom")
		(35 "F.Fab" user "Ref Des/Assembly Top")
		(33 "B.Fab" user "Ref Des/Assembly Bottom")
	)
	(footprint ""
		(layer "F.Cu")
		(at 115.316 -20.0406 180)
		(property "Reference" "R703"
			(at 0 0 180)
			(layer "F.SilkS")
			(hide yes)
			(effects
				(font
					(size 1.27 1.27)
				)
			)
		)
		(property "Value" "4K7R2F-GP"
			(at 0.064008 -3.993896 180)
			(unlocked yes)
			(layer "F.Fab")
			(hide yes)
			(effects
				(font
					(size 1.016 1.016)
					(thickness 0.1524)
				)
			)
		)
		(property "Device Type" "R402H16"
			(at 0.064008 -5.517896 180)
			(unlocked yes)
			(layer "F.Fab")
			(hide yes)
			(effects
				(font
					(size 1.016 1.016)
					(thickness 0.1524)
				)
			)
		)
		(duplicate_pad_numbers_are_jumpers no)
		(fp_line
			(start 0.508 -0.9398)
			(end -0.508 -0.9398)
			(stroke
				(width 0.1524)
				(type default)
			)
			(layer "F.SilkS")
		)
		(fp_line
			(start -0.508 -0.9398)
			(end -0.508 0.9398)
			(stroke
				(width 0.1524)
				(type default)
			)
			(layer "F.SilkS")
		)
		(fp_rect
			(start -0.508 0.9398)
			(end 0.508 -0.9398)
			(stroke
				(width 0)
				(type default)
			)
			(fill no)
			(layer "F.CrtYd")
		)
		(fp_rect
			(start -0.508 0.9398)
			(end 0.508 -0.9398)
			(stroke
				(width 0)
				(type default)
			)
			(fill no)
			(layer "F.Fab")
		)
		(pad "1" smd custom
			(at 0 -0.4445 180)
			(size 0.1397 0.1397)
			(layers "F.Cu" "F.Mask" "F.Paste")
			(net "SW_PWR_R_HDD27")
			(options
				(clearance outline)
				(anchor circle)
			)
			(primitives
				(gr_poly
					(pts
						(arc
							(start -0.1778 -0.2794)
							(mid -0.249642 -0.249642)
							(end -0.2794 -0.1778)
						)
						(arc
							(start -0.2794 0.1778)
							(mid -0.249642 0.249642)
							(end -0.1778 0.2794)
						)
						(arc
							(start 0.1778 0.2794)
							(mid 0.249642 0.249642)
							(end 0.2794 0.1778)
						)
						(arc
							(start 0.2794 -0.1778)
							(mid 0.249642 -0.249642)
							(end 0.1778 -0.2794)
						)
					)
					(width 0)
					(fill yes)
				)
			)
		)
		(pad "2" smd custom
			(at 0 0.4445 180)
			(size 0.1397 0.1397)
			(layers "F.Cu" "F.Mask" "F.Paste")
			(net "GND")
			(options
				(clearance outline)
				(anchor circle)
			)
			(primitives
				(gr_poly
					(pts
						(arc
							(start -0.1778 -0.2794)
							(mid -0.249642 -0.249642)
							(end -0.2794 -0.1778)
						)
						(arc
							(start -0.2794 0.1778)
							(mid -0.249642 0.249642)
							(end -0.1778 0.2794)
						)
						(arc
							(start 0.1778 0.2794)
							(mid 0.249642 0.249642)
							(end 0.2794 0.1778)
						)
						(arc
							(start 0.2794 -0.1778)
							(mid 0.249642 -0.249642)
							(end 0.1778 -0.2794)
						)
					)
					(width 0)
					(fill yes)
				)
			)
		)
	)
	(footprint ""
		(layer "F.Cu")
		(at 456.3618 -229.50932 180)
		(property "Reference" "R1153"
			(at 0 0 180)
			(layer "F.SilkS")
			(hide yes)
			(effects
				(font
					(size 1.27 1.27)
				)
			)
		)
		(property "Value" "0R2J-2-GP"
			(at 0.064008 -3.993896 180)
			(unlocked yes)
			(layer "F.Fab")
			(hide yes)
			(effects
				(font
					(size 1.016 1.016)
					(thickness 0.1524)
				)
			)
		)
		(property "Device Type" "R402H16"
			(at 0.064008 -5.517896 180)
			(unlocked yes)
			(layer "F.Fab")
			(hide yes)
			(effects
				(font
					(size 1.016 1.016)
					(thickness 0.1524)
				)
			)
		)
		(duplicate_pad_numbers_are_jumpers no)
		(fp_line
			(start 0.508 -0.9398)
			(end -0.508 -0.9398)
			(stroke
				(width 0.1524)
				(type default)
			)
			(layer "F.SilkS")
		)
		(fp_line
			(start -0.508 -0.9398)
			(end -0.508 0.9398)
			(stroke
				(width 0.1524)
				(type default)
			)
			(layer "F.SilkS")
		)
		(fp_rect
			(start -0.508 0.9398)
			(end 0.508 -0.9398)
			(stroke
				(width 0)
				(type default)
			)
			(fill no)
			(layer "F.CrtYd")
		)
		(fp_rect
			(start -0.508 0.9398)
			(end 0.508 -0.9398)
			(stroke
				(width 0)
				(type default)
			)
			(fill no)
			(layer "F.Fab")
		)
		(pad "1" smd custom
			(at 0 -0.4445 180)
			(size 0.1397 0.1397)
			(layers "F.Cu" "F.Mask" "F.Paste")
			(net "P5V_B_3_ROVP")
			(options
				(clearance outline)
				(anchor circle)
			)
			(primitives
				(gr_poly
					(pts
						(arc
							(start -0.1778 -0.2794)
							(mid -0.249642 -0.249642)
							(end -0.2794 -0.1778)
						)
						(arc
							(start -0.2794 0.1778)
							(mid -0.249642 0.249642)
							(end -0.1778 0.2794)
						)
						(arc
							(start 0.1778 0.2794)
							(mid 0.249642 0.249642)
							(end 0.2794 0.1778)
						)
						(arc
							(start 0.2794 -0.1778)
							(mid 0.249642 -0.249642)
							(end 0.1778 -0.2794)
						)
					)
					(width 0)
					(fill yes)
				)
			)
		)
		(pad "2" smd custom
			(at 0 0.4445 180)
			(size 0.1397 0.1397)
			(layers "F.Cu" "F.Mask" "F.Paste")
			(net "AGND_P5V_B_3")
			(options
				(clearance outline)
				(anchor circle)
			)
			(primitives
				(gr_poly
					(pts
						(arc
							(start -0.1778 -0.2794)
							(mid -0.249642 -0.249642)
							(end -0.2794 -0.1778)
						)
						(arc
							(start -0.2794 0.1778)
							(mid -0.249642 0.249642)
							(end -0.1778 0.2794)
						)
						(arc
							(start 0.1778 0.2794)
							(mid 0.249642 0.249642)
							(end 0.2794 0.1778)
						)
						(arc
							(start 0.2794 -0.1778)
							(mid 0.249642 -0.249642)
							(end 0.1778 -0.2794)
						)
					)
					(width 0)
					(fill yes)
				)
			)
		)
	)
	(footprint ""
		(layer "F.Cu")
		(at 239.780064 -367.607088)
		(property "Reference" "R1025"
			(at 0 0 0)
			(layer "F.SilkS")
			(hide yes)
			(effects
				(font
					(size 1.27 1.27)
				)
			)
		)
		(property "Value" "100R2D-GP"
			(at 0.064008 -3.993896 0)
			(unlocked yes)
			(layer "F.Fab")
			(hide yes)
			(effects
				(font
					(size 1.016 1.016)
					(thickness 0.1524)
				)
			)
		)
		(property "Device Type" "R402H14"
			(at 0.064008 -5.517896 0)
			(unlocked yes)
			(layer "F.Fab")
			(hide yes)
			(effects
				(font
					(size 1.016 1.016)
					(thickness 0.1524)
				)
			)
		)
		(duplicate_pad_numbers_are_jumpers no)
		(fp_line
			(start -0.508 -0.9398)
			(end -0.508 0.9398)
			(stroke
				(width 0.1524)
				(type default)
			)
			(layer "F.SilkS")
		)
		(fp_line
			(start 0.508 -0.9398)
			(end -0.508 -0.9398)
			(stroke
				(width 0.1524)
				(type default)
			)
			(layer "F.SilkS")
		)
		(fp_rect
			(start -0.508 0.9398)
			(end 0.508 -0.9398)
			(stroke
				(width 0)
				(type default)
			)
			(fill no)
			(layer "F.CrtYd")
		)
		(fp_rect
			(start -0.508 0.9398)
			(end 0.508 -0.9398)
			(stroke
				(width 0)
				(type default)
			)
			(fill no)
			(layer "F.Fab")
		)
		(pad "1" smd custom
			(at 0 -0.4445)
			(size 0.1397 0.1397)
			(layers "F.Cu" "F.Mask" "F.Paste")
			(net "GND")
			(options
				(clearance outline)
				(anchor circle)
			)
			(primitives
				(gr_poly
					(pts
						(arc
							(start -0.1778 -0.2794)
							(mid -0.249642 -0.249642)
							(end -0.2794 -0.1778)
						)
						(arc
							(start -0.2794 0.1778)
							(mid -0.249642 0.249642)
							(end -0.1778 0.2794)
						)
						(arc
							(start 0.1778 0.2794)
							(mid 0.249642 0.249642)
							(end 0.2794 0.1778)
						)
						(arc
							(start 0.2794 -0.1778)
							(mid 0.249642 -0.249642)
							(end 0.1778 -0.2794)
						)
					)
					(width 0)
					(fill yes)
				)
			)
		)
		(pad "2" smd custom
			(at 0 0.4445)
			(size 0.1397 0.1397)
			(layers "F.Cu" "F.Mask" "F.Paste")
			(net "MB3_TEMP_E")
			(options
				(clearance outline)
				(anchor circle)
			)
			(primitives
				(gr_poly
					(pts
						(arc
							(start -0.1778 -0.2794)
							(mid -0.249642 -0.249642)
							(end -0.2794 -0.1778)
						)
						(arc
							(start -0.2794 0.1778)
							(mid -0.249642 0.249642)
							(end -0.1778 0.2794)
						)
						(arc
							(start 0.1778 0.2794)
							(mid 0.249642 0.249642)
							(end 0.2794 0.1778)
						)
						(arc
							(start 0.2794 -0.1778)
							(mid 0.249642 -0.249642)
							(end 0.1778 -0.2794)
						)
					)
					(width 0)
					(fill yes)
				)
			)
		)
	)
	(footprint ""
		(layer "F.Cu")
		(at 111.76 -99.314)
		(property "Reference" "R410"
			(at 0 0 0)
			(layer "F.SilkS")
			(hide yes)
			(effects
				(font
					(size 1.27 1.27)
				)
			)
		)
		(property "Value" "130R3F-GP"
			(at -0.0254 -2.5146 0)
			(unlocked yes)
			(layer "F.Fab")
			(hide yes)
			(effects
				(font
					(size 1.016 1.016)
					(thickness 0.1524)
				)
			)
		)
		(property "Device Type" "R603H22"
			(at -0.0254 -4.0386 0)
			(unlocked yes)
			(layer "F.Fab")
			(hide yes)
			(effects
				(font
					(size 1.016 1.016)
					(thickness 0.1524)
				)
			)
		)
		(duplicate_pad_numbers_are_jumpers no)
		(fp_line
			(start -0.4826 0)
			(end -0.2032 0)
			(stroke
				(width 0.2032)
				(type default)
			)
			(layer "F.SilkS")
		)
		(fp_line
			(start 0.2032 0)
			(end 0.4826 0)
			(stroke
				(width 0.2032)
				(type default)
			)
			(layer "F.SilkS")
		)
		(fp_rect
			(start -0.5842 1.3335)
			(end 0.5842 -1.3335)
			(stroke
				(width 0)
				(type default)
			)
			(fill no)
			(layer "F.CrtYd")
		)
		(fp_rect
			(start -0.5842 1.3335)
			(end 0.5842 -1.3335)
			(stroke
				(width 0)
				(type default)
			)
			(fill no)
			(layer "F.Fab")
		)
		(pad "1" smd custom
			(at 0 -0.762)
			(size 0.2159 0.2159)
			(layers "F.Cu" "F.Mask" "F.Paste")
			(net "P5V_B_2")
			(options
				(clearance outline)
				(anchor circle)
			)
			(primitives
				(gr_poly
					(pts
						(arc
							(start -0.3302 -0.4318)
							(mid -0.402042 -0.402042)
							(end -0.4318 -0.3302)
						)
						(arc
							(start -0.4318 0.3302)
							(mid -0.402042 0.402042)
							(end -0.3302 0.4318)
						)
						(arc
							(start 0.3302 0.4318)
							(mid 0.402042 0.402042)
							(end 0.4318 0.3302)
						)
						(arc
							(start 0.4318 -0.3302)
							(mid 0.402042 -0.402042)
							(end 0.3302 -0.4318)
						)
					)
					(width 0)
					(fill yes)
				)
			)
		)
		(pad "2" smd custom
			(at 0 0.762)
			(size 0.2159 0.2159)
			(layers "F.Cu" "F.Mask" "F.Paste")
			(net "FLT_HDD15")
			(options
				(clearance outline)
				(anchor circle)
			)
			(primitives
				(gr_poly
					(pts
						(arc
							(start -0.3302 -0.4318)
							(mid -0.402042 -0.402042)
							(end -0.4318 -0.3302)
						)
						(arc
							(start -0.4318 0.3302)
							(mid -0.402042 0.402042)
							(end -0.3302 0.4318)
						)
						(arc
							(start 0.3302 0.4318)
							(mid 0.402042 0.402042)
							(end 0.4318 0.3302)
						)
						(arc
							(start 0.4318 -0.3302)
							(mid 0.402042 -0.402042)
							(end 0.3302 -0.4318)
						)
					)
					(width 0)
					(fill yes)
				)
			)
		)
	)
	(footprint ""
		(layer "F.Cu")
		(at 260.462522 -368.655346 90)
		(property "Reference" "R1028"
			(at 0 0 90)
			(layer "F.SilkS")
			(hide yes)
			(effects
				(font
					(size 1.27 1.27)
				)
			)
		)
		(property "Value" "0R2J-2-GP"
			(at 0.064008 -3.993896 90)
			(unlocked yes)
			(layer "F.Fab")
			(hide yes)
			(effects
				(font
					(size 1.016 1.016)
					(thickness 0.1524)
				)
			)
		)
		(property "Device Type" "R402H16"
			(at 0.064008 -5.517896 90)
			(unlocked yes)
			(layer "F.Fab")
			(hide yes)
			(effects
				(font
					(size 1.016 1.016)
					(thickness 0.1524)
				)
			)
		)
		(duplicate_pad_numbers_are_jumpers no)
		(fp_line
			(start 0.508 -0.9398)
			(end -0.508 -0.9398)
			(stroke
				(width 0.1524)
				(type default)
			)
			(layer "F.SilkS")
		)
		(fp_line
			(start -0.508 -0.9398)
			(end -0.508 0.9398)
			(stroke
				(width 0.1524)
				(type default)
			)
			(layer "F.SilkS")
		)
		(fp_rect
			(start -0.508 0.9398)
			(end 0.508 -0.9398)
			(stroke
				(width 0)
				(type default)
			)
			(fill no)
			(layer "F.CrtYd")
		)
		(fp_rect
			(start -0.508 0.9398)
			(end 0.508 -0.9398)
			(stroke
				(width 0)
				(type default)
			)
			(fill no)
			(layer "F.Fab")
		)
		(pad "1" smd custom
			(at 0 -0.4445 90)
			(size 0.1397 0.1397)
			(layers "F.Cu" "F.Mask" "F.Paste")
			(net "MB3_SDA_R")
			(options
				(clearance outline)
				(anchor circle)
			)
			(primitives
				(gr_poly
					(pts
						(arc
							(start -0.1778 -0.2794)
							(mid -0.249642 -0.249642)
							(end -0.2794 -0.1778)
						)
						(arc
							(start -0.2794 0.1778)
							(mid -0.249642 0.249642)
							(end -0.1778 0.2794)
						)
						(arc
							(start 0.1778 0.2794)
							(mid 0.249642 0.249642)
							(end 0.2794 0.1778)
						)
						(arc
							(start 0.2794 -0.1778)
							(mid 0.249642 -0.249642)
							(end 0.1778 -0.2794)
						)
					)
					(width 0)
					(fill yes)
				)
			)
		)
		(pad "2" smd custom
			(at 0 0.4445 90)
			(size 0.1397 0.1397)
			(layers "F.Cu" "F.Mask" "F.Paste")
			(net "I2C_DPB_B_SDA_BUF")
			(options
				(clearance outline)
				(anchor circle)
			)
			(primitives
				(gr_poly
					(pts
						(arc
							(start -0.1778 -0.2794)
							(mid -0.249642 -0.249642)
							(end -0.2794 -0.1778)
						)
						(arc
							(start -0.2794 0.1778)
							(mid -0.249642 0.249642)
							(end -0.1778 0.2794)
						)
						(arc
							(start 0.1778 0.2794)
							(mid 0.249642 0.249642)
							(end 0.2794 0.1778)
						)
						(arc
							(start 0.2794 -0.1778)
							(mid 0.249642 -0.249642)
							(end 0.1778 -0.2794)
						)
					)
					(width 0)
					(fill yes)
				)
			)
		)
	)
	(footprint ""
		(layer "F.Cu")
		(at 78.359 -133.096 180)
		(property "Reference" "R408"
			(at 0 0 180)
			(layer "F.SilkS")
			(hide yes)
			(effects
				(font
					(size 1.27 1.27)
				)
			)
		)
		(property "Value" "200KR2F-L-GP"
			(at 0.064008 -3.993896 180)
			(unlocked yes)
			(layer "F.Fab")
			(hide yes)
			(effects
				(font
					(size 1.016 1.016)
					(thickness 0.1524)
				)
			)
		)
		(property "Device Type" "R402H16"
			(at 0.064008 -5.517896 180)
			(unlocked yes)
			(layer "F.Fab")
			(hide yes)
			(effects
				(font
					(size 1.016 1.016)
					(thickness 0.1524)
				)
			)
		)
		(duplicate_pad_numbers_are_jumpers no)
		(fp_line
			(start 0.508 -0.9398)
			(end -0.508 -0.9398)
			(stroke
				(width 0.1524)
				(type default)
			)
			(layer "F.SilkS")
		)
		(fp_line
			(start -0.508 -0.9398)
			(end -0.508 0.9398)
			(stroke
				(width 0.1524)
				(type default)
			)
			(layer "F.SilkS")
		)
		(fp_rect
			(start -0.508 0.9398)
			(end 0.508 -0.9398)
			(stroke
				(width 0)
				(type default)
			)
			(fill no)
			(layer "F.CrtYd")
		)
		(fp_rect
			(start -0.508 0.9398)
			(end 0.508 -0.9398)
			(stroke
				(width 0)
				(type default)
			)
			(fill no)
			(layer "F.Fab")
		)
		(pad "1" smd custom
			(at 0 -0.4445 180)
			(size 0.1397 0.1397)
			(layers "F.Cu" "F.Mask" "F.Paste")
			(net "SW_HDD_R14")
			(options
				(clearance outline)
				(anchor circle)
			)
			(primitives
				(gr_poly
					(pts
						(arc
							(start -0.1778 -0.2794)
							(mid -0.249642 -0.249642)
							(end -0.2794 -0.1778)
						)
						(arc
							(start -0.2794 0.1778)
							(mid -0.249642 0.249642)
							(end -0.1778 0.2794)
						)
						(arc
							(start 0.1778 0.2794)
							(mid 0.249642 0.249642)
							(end 0.2794 0.1778)
						)
						(arc
							(start 0.2794 -0.1778)
							(mid 0.249642 -0.249642)
							(end 0.1778 -0.2794)
						)
					)
					(width 0)
					(fill yes)
				)
			)
		)
		(pad "2" smd custom
			(at 0 0.4445 180)
			(size 0.1397 0.1397)
			(layers "F.Cu" "F.Mask" "F.Paste")
			(net "SW_HDD_N14")
			(options
				(clearance outline)
				(anchor circle)
			)
			(primitives
				(gr_poly
					(pts
						(arc
							(start -0.1778 -0.2794)
							(mid -0.249642 -0.249642)
							(end -0.2794 -0.1778)
						)
						(arc
							(start -0.2794 0.1778)
							(mid -0.249642 0.249642)
							(end -0.1778 0.2794)
						)
						(arc
							(start 0.1778 0.2794)
							(mid 0.249642 0.249642)
							(end 0.2794 0.1778)
						)
						(arc
							(start 0.2794 -0.1778)
							(mid 0.249642 -0.249642)
							(end 0.1778 -0.2794)
						)
					)
					(width 0)
					(fill yes)
				)
			)
		)
	)
	(footprint ""
		(layer "F.Cu")
		(at 46.355 -139.446 -90)
		(property "Reference" "R384"
			(at 0 0 270)
			(layer "F.SilkS")
			(hide yes)
			(effects
				(font
					(size 1.27 1.27)
				)
			)
		)
		(property "Value" "300KR2F-GP"
			(at 0.064008 -3.993896 270)
			(unlocked yes)
			(layer "F.Fab")
			(hide yes)
			(effects
				(font
					(size 1.016 1.016)
					(thickness 0.1524)
				)
			)
		)
		(property "Device Type" "R402H16"
			(at 0.064008 -5.517896 270)
			(unlocked yes)
			(layer "F.Fab")
			(hide yes)
			(effects
				(font
					(size 1.016 1.016)
					(thickness 0.1524)
				)
			)
		)
		(duplicate_pad_numbers_are_jumpers no)
		(fp_line
			(start -0.508 -0.9398)
			(end -0.508 0.9398)
			(stroke
				(width 0.1524)
				(type default)
			)
			(layer "F.SilkS")
		)
		(fp_line
			(start 0.508 -0.9398)
			(end -0.508 -0.9398)
			(stroke
				(width 0.1524)
				(type default)
			)
			(layer "F.SilkS")
		)
		(fp_rect
			(start -0.508 0.9398)
			(end 0.508 -0.9398)
			(stroke
				(width 0)
				(type default)
			)
			(fill no)
			(layer "F.CrtYd")
		)
		(fp_rect
			(start -0.508 0.9398)
			(end 0.508 -0.9398)
			(stroke
				(width 0)
				(type default)
			)
			(fill no)
			(layer "F.Fab")
		)
		(pad "1" smd custom
			(at 0 -0.4445 270)
			(size 0.1397 0.1397)
			(layers "F.Cu" "F.Mask" "F.Paste")
			(net "SW_HDD_N13")
			(options
				(clearance outline)
				(anchor circle)
			)
			(primitives
				(gr_poly
					(pts
						(arc
							(start -0.1778 -0.2794)
							(mid -0.249642 -0.249642)
							(end -0.2794 -0.1778)
						)
						(arc
							(start -0.2794 0.1778)
							(mid -0.249642 0.249642)
							(end -0.1778 0.2794)
						)
						(arc
							(start 0.1778 0.2794)
							(mid 0.249642 0.249642)
							(end 0.2794 0.1778)
						)
						(arc
							(start 0.2794 -0.1778)
							(mid 0.249642 -0.249642)
							(end 0.1778 -0.2794)
						)
					)
					(width 0)
					(fill yes)
				)
			)
		)
		(pad "2" smd custom
			(at 0 0.4445 270)
			(size 0.1397 0.1397)
			(layers "F.Cu" "F.Mask" "F.Paste")
			(net "P12V_B")
			(options
				(clearance outline)
				(anchor circle)
			)
			(primitives
				(gr_poly
					(pts
						(arc
							(start -0.1778 -0.2794)
							(mid -0.249642 -0.249642)
							(end -0.2794 -0.1778)
						)
						(arc
							(start -0.2794 0.1778)
							(mid -0.249642 0.249642)
							(end -0.1778 0.2794)
						)
						(arc
							(start 0.1778 0.2794)
							(mid 0.249642 0.249642)
							(end 0.2794 0.1778)
						)
						(arc
							(start 0.2794 -0.1778)
							(mid 0.249642 -0.249642)
							(end 0.1778 -0.2794)
						)
					)
					(width 0)
					(fill yes)
				)
			)
		)
	)
)
